FILE_TYPE = CONNECTIVITY;
{Allegro Design Entry HDL 17.4-2019 S026 (4007227) 1/17/2022}
"PAGE_NUMBER" = 445;
0"NC";
END.
